(kicad_pcb
	(version 20260206)
	(generator "pcbnew")
	(generator_version "10.0")
	(general
		(thickness 1.6)
		(legacy_teardrops no)
	)
	(paper "A4")
	(title_block
		(title "12092022_DA0F0TFB6D0_F0T_FAN_BOARD_MP5048_D_brd_v02_OCP.brd")
		(comment 1 "Grand Teton / footprints 792-797 of 924")
	)
	(layers
		(0 "F.Cu" signal "TOP")
		(4 "In1.Cu" signal "GND")
		(6 "In2.Cu" signal "IN1")
		(8 "In3.Cu" signal "IN2")
		(10 "In4.Cu" signal "GND1")
		(2 "B.Cu" signal "BOTTOM")
		(9 "F.Adhes" user "F.Adhesive")
		(11 "B.Adhes" user "B.Adhesive")
		(13 "F.Paste" user "Package Geometry/Pastemask Top")
		(15 "B.Paste" user "Package Geometry/Pastemask Bottom")
		(5 "F.SilkS" user "Ref Des/Silkscreen Top")
		(7 "B.SilkS" user "Ref Des/Silkscreen Bottom")
		(1 "F.Mask" user "Board Geometry/Soldermask Top")
		(3 "B.Mask" user "Board Geometry/Soldermask Bottom")
		(17 "Dwgs.User" user "User.Drawings")
		(19 "Cmts.User" user "User.Comments")
		(21 "Eco1.User" user "User.Eco1")
		(23 "Eco2.User" user "User.Eco2")
		(25 "Edge.Cuts" user "Board Geometry/Outline")
		(27 "Margin" user)
		(31 "F.CrtYd" user "Package Geometry/Place Bound Top")
		(29 "B.CrtYd" user "Package Geometry/Place Bound Bottom")
		(35 "F.Fab" user "Ref Des/Assembly Top")
		(33 "B.Fab" user "Ref Des/Assembly Bottom")
	)
	(footprint ""
		(layer "B.Cu")
		(at 34.666428 -67.621912 90)
		(property "Reference" "U391"
			(at -1.327912 -1.900428 270)
			(unlocked yes)
			(layer "B.SilkS")
			(effects
				(font
					(size 0.7874 0.5842)
					(thickness 0.1524)
				)
				(justify left mirror)
			)
		)
		(property "Value" ""
			(at 0 0 90)
			(layer "B.Fab")
			(effects
				(font
					(size 1.27 1.27)
				)
				(justify mirror)
			)
		)
		(duplicate_pad_numbers_are_jumpers no)
		(fp_line
			(start 1.3462 -1.1938)
			(end 1.3462 1.1684)
			(stroke
				(width 0.1524)
				(type default)
			)
			(layer "B.SilkS")
		)
		(fp_line
			(start -1.3462 -1.1938)
			(end 1.3462 -1.1938)
			(stroke
				(width 0.1524)
				(type default)
			)
			(layer "B.SilkS")
		)
		(fp_line
			(start 1.3462 1.1938)
			(end -1.3462 1.1938)
			(stroke
				(width 0.1524)
				(type default)
			)
			(layer "B.SilkS")
		)
		(fp_line
			(start -1.3462 1.1938)
			(end -1.3462 -1.1938)
			(stroke
				(width 0.1524)
				(type default)
			)
			(layer "B.SilkS")
		)
		(fp_poly
			(pts
				(xy 1.447038 -0.760476) (xy 2.052066 -0.457962) (xy 2.052066 -1.06299)
			)
			(stroke
				(width 0)
				(type default)
			)
			(fill yes)
			(layer "B.SilkS")
		)
		(fp_line
			(start 0.674878 -1.124966)
			(end 0.674878 1.124966)
			(stroke
				(width 0.1)
				(type default)
			)
			(layer "B.Fab")
		)
		(fp_line
			(start -0.674878 -1.124966)
			(end 0.674878 -1.124966)
			(stroke
				(width 0.1)
				(type default)
			)
			(layer "B.Fab")
		)
		(fp_line
			(start 0.674878 1.124966)
			(end -0.674878 1.124966)
			(stroke
				(width 0.1)
				(type default)
			)
			(layer "B.Fab")
		)
		(fp_line
			(start -0.674878 1.124966)
			(end -0.674878 -1.124966)
			(stroke
				(width 0.1)
				(type default)
			)
			(layer "B.Fab")
		)
		(fp_poly
			(pts
				(xy 1.447038 -0.760476) (xy 2.052066 -0.457962) (xy 2.052066 -1.06299)
			)
			(stroke
				(width 0)
				(type default)
			)
			(fill yes)
			(layer "B.Fab")
		)
		(pad "1" smd rect
			(at 0.899922 -0.750062 270)
			(size 0.6096 0.6096)
			(layers "B.Cu" "B.Mask" "B.Paste")
			(net "NC_U391_P1")
		)
		(pad "2" smd rect
			(at 0.899922 0 180)
			(size 0.4064 0.6096)
			(layers "B.Cu" "B.Mask" "B.Paste")
			(net "FAN_3_PRSNT_BUF_N")
		)
		(pad "3" smd rect
			(at 0.899922 0.750062 270)
			(size 0.6096 0.6096)
			(layers "B.Cu" "B.Mask" "B.Paste")
			(net "GND")
		)
		(pad "4" smd rect
			(at -0.899922 0.750062 270)
			(size 0.6096 0.6096)
			(layers "B.Cu" "B.Mask" "B.Paste")
			(net "FAN_3_PRESENT")
		)
		(pad "5" smd rect
			(at -0.899922 -0.750062 270)
			(size 0.6096 0.6096)
			(layers "B.Cu" "B.Mask" "B.Paste")
			(net "P3V3_AUX")
		)
	)
	(footprint ""
		(layer "B.Cu")
		(at 45.085 -258.572 90)
		(property "Reference" "PC5"
			(at 0 0 90)
			(layer "B.SilkS")
			(hide yes)
			(effects
				(font
					(size 1.27 1.27)
				)
				(justify mirror)
			)
		)
		(property "Value" ""
			(at 0 0 90)
			(layer "B.Fab")
			(effects
				(font
					(size 1.27 1.27)
				)
				(justify mirror)
			)
		)
		(duplicate_pad_numbers_are_jumpers no)
		(fp_line
			(start 0.7874 -0.4064)
			(end -0.7874 -0.4064)
			(stroke
				(width 0.1524)
				(type default)
			)
			(layer "B.SilkS")
		)
		(fp_line
			(start -0.7874 -0.4064)
			(end -0.7874 0.4064)
			(stroke
				(width 0.1524)
				(type default)
			)
			(layer "B.SilkS")
		)
		(fp_line
			(start 0.7874 0.4064)
			(end 0.7874 -0.4064)
			(stroke
				(width 0.1524)
				(type default)
			)
			(layer "B.SilkS")
		)
		(fp_line
			(start -0.7874 0.4064)
			(end 0.7874 0.4064)
			(stroke
				(width 0.1524)
				(type default)
			)
			(layer "B.SilkS")
		)
		(fp_line
			(start 0.67945 -0.305054)
			(end 0.12065 -0.305054)
			(stroke
				(width 0.1)
				(type default)
			)
			(layer "B.Fab")
		)
		(fp_line
			(start 0.12065 -0.305054)
			(end 0.12065 -0.2794)
			(stroke
				(width 0.1)
				(type default)
			)
			(layer "B.Fab")
		)
		(fp_line
			(start -0.12065 -0.3048)
			(end -0.67945 -0.3048)
			(stroke
				(width 0.1)
				(type default)
			)
			(layer "B.Fab")
		)
		(fp_line
			(start -0.67945 -0.3048)
			(end -0.67945 0.3048)
			(stroke
				(width 0.1)
				(type default)
			)
			(layer "B.Fab")
		)
		(fp_line
			(start 0.12065 -0.2794)
			(end -0.12065 -0.2794)
			(stroke
				(width 0.1)
				(type default)
			)
			(layer "B.Fab")
		)
		(fp_line
			(start -0.12065 -0.2794)
			(end -0.12065 -0.3048)
			(stroke
				(width 0.1)
				(type default)
			)
			(layer "B.Fab")
		)
		(fp_line
			(start 0.12065 0.2794)
			(end 0.12065 0.3048)
			(stroke
				(width 0.1)
				(type default)
			)
			(layer "B.Fab")
		)
		(fp_line
			(start -0.120396 0.2794)
			(end 0.12065 0.2794)
			(stroke
				(width 0.1)
				(type default)
			)
			(layer "B.Fab")
		)
		(fp_line
			(start 0.67945 0.3048)
			(end 0.67945 -0.305054)
			(stroke
				(width 0.1)
				(type default)
			)
			(layer "B.Fab")
		)
		(fp_line
			(start 0.12065 0.3048)
			(end 0.67945 0.3048)
			(stroke
				(width 0.1)
				(type default)
			)
			(layer "B.Fab")
		)
		(fp_line
			(start -0.120396 0.3048)
			(end -0.120396 0.2794)
			(stroke
				(width 0.1)
				(type default)
			)
			(layer "B.Fab")
		)
		(fp_line
			(start -0.67945 0.3048)
			(end -0.120396 0.3048)
			(stroke
				(width 0.1)
				(type default)
			)
			(layer "B.Fab")
		)
		(pad "1" smd circle
			(at 0.40005 0 270)
			(size 0 0)
			(layers "B.Cu" "B.Mask" "B.Paste")
			(net "FAN_0_SS")
		)
		(pad "2" smd circle
			(at -0.40005 0 270)
			(size 0 0)
			(layers "B.Cu" "B.Mask" "B.Paste")
			(net "GND")
		)
	)
	(footprint ""
		(layer "B.Cu")
		(at 47.117 -258.572 90)
		(property "Reference" "PR6"
			(at 0 0 90)
			(layer "B.SilkS")
			(hide yes)
			(effects
				(font
					(size 1.27 1.27)
				)
				(justify mirror)
			)
		)
		(property "Value" ""
			(at 0 0 90)
			(layer "B.Fab")
			(effects
				(font
					(size 1.27 1.27)
				)
				(justify mirror)
			)
		)
		(duplicate_pad_numbers_are_jumpers no)
		(fp_line
			(start 0.7874 -0.4064)
			(end -0.7874 -0.4064)
			(stroke
				(width 0.1524)
				(type default)
			)
			(layer "B.SilkS")
		)
		(fp_line
			(start -0.7874 -0.4064)
			(end -0.7874 0.4064)
			(stroke
				(width 0.1524)
				(type default)
			)
			(layer "B.SilkS")
		)
		(fp_line
			(start 0.7874 0.4064)
			(end 0.7874 -0.4064)
			(stroke
				(width 0.1524)
				(type default)
			)
			(layer "B.SilkS")
		)
		(fp_line
			(start -0.7874 0.4064)
			(end 0.7874 0.4064)
			(stroke
				(width 0.1524)
				(type default)
			)
			(layer "B.SilkS")
		)
		(fp_line
			(start 0.67945 -0.305054)
			(end 0.12065 -0.305054)
			(stroke
				(width 0.1)
				(type default)
			)
			(layer "B.Fab")
		)
		(fp_line
			(start 0.12065 -0.305054)
			(end 0.12065 -0.2794)
			(stroke
				(width 0.1)
				(type default)
			)
			(layer "B.Fab")
		)
		(fp_line
			(start -0.12065 -0.3048)
			(end -0.67945 -0.3048)
			(stroke
				(width 0.1)
				(type default)
			)
			(layer "B.Fab")
		)
		(fp_line
			(start -0.67945 -0.3048)
			(end -0.67945 0.3048)
			(stroke
				(width 0.1)
				(type default)
			)
			(layer "B.Fab")
		)
		(fp_line
			(start 0.12065 -0.2794)
			(end -0.12065 -0.2794)
			(stroke
				(width 0.1)
				(type default)
			)
			(layer "B.Fab")
		)
		(fp_line
			(start -0.12065 -0.2794)
			(end -0.12065 -0.3048)
			(stroke
				(width 0.1)
				(type default)
			)
			(layer "B.Fab")
		)
		(fp_line
			(start 0.12065 0.2794)
			(end 0.12065 0.3048)
			(stroke
				(width 0.1)
				(type default)
			)
			(layer "B.Fab")
		)
		(fp_line
			(start -0.120396 0.2794)
			(end 0.12065 0.2794)
			(stroke
				(width 0.1)
				(type default)
			)
			(layer "B.Fab")
		)
		(fp_line
			(start 0.67945 0.3048)
			(end 0.67945 -0.305054)
			(stroke
				(width 0.1)
				(type default)
			)
			(layer "B.Fab")
		)
		(fp_line
			(start 0.12065 0.3048)
			(end 0.67945 0.3048)
			(stroke
				(width 0.1)
				(type default)
			)
			(layer "B.Fab")
		)
		(fp_line
			(start -0.120396 0.3048)
			(end -0.120396 0.2794)
			(stroke
				(width 0.1)
				(type default)
			)
			(layer "B.Fab")
		)
		(fp_line
			(start -0.67945 0.3048)
			(end -0.120396 0.3048)
			(stroke
				(width 0.1)
				(type default)
			)
			(layer "B.Fab")
		)
		(pad "1" smd circle
			(at 0.40005 0 270)
			(size 0 0)
			(layers "B.Cu" "B.Mask" "B.Paste")
			(net "FAN_0_CS")
		)
		(pad "2" smd circle
			(at -0.40005 0 270)
			(size 0 0)
			(layers "B.Cu" "B.Mask" "B.Paste")
			(net "GND")
		)
	)
	(footprint ""
		(layer "B.Cu")
		(at 9.667494 -258.562856 90)
		(property "Reference" "PC2125"
			(at 0 0 90)
			(layer "B.SilkS")
			(hide yes)
			(effects
				(font
					(size 1.27 1.27)
				)
				(justify mirror)
			)
		)
		(property "Value" ""
			(at 0 0 90)
			(layer "B.Fab")
			(effects
				(font
					(size 1.27 1.27)
				)
				(justify mirror)
			)
		)
		(duplicate_pad_numbers_are_jumpers no)
		(fp_line
			(start 0.7874 -0.4064)
			(end -0.7874 -0.4064)
			(stroke
				(width 0.1524)
				(type default)
			)
			(layer "B.SilkS")
		)
		(fp_line
			(start -0.7874 -0.4064)
			(end -0.7874 0.4064)
			(stroke
				(width 0.1524)
				(type default)
			)
			(layer "B.SilkS")
		)
		(fp_line
			(start 0.7874 0.4064)
			(end 0.7874 -0.4064)
			(stroke
				(width 0.1524)
				(type default)
			)
			(layer "B.SilkS")
		)
		(fp_line
			(start -0.7874 0.4064)
			(end 0.7874 0.4064)
			(stroke
				(width 0.1524)
				(type default)
			)
			(layer "B.SilkS")
		)
		(fp_line
			(start 0.67945 -0.305054)
			(end 0.12065 -0.305054)
			(stroke
				(width 0.1)
				(type default)
			)
			(layer "B.Fab")
		)
		(fp_line
			(start 0.12065 -0.305054)
			(end 0.12065 -0.2794)
			(stroke
				(width 0.1)
				(type default)
			)
			(layer "B.Fab")
		)
		(fp_line
			(start -0.12065 -0.3048)
			(end -0.67945 -0.3048)
			(stroke
				(width 0.1)
				(type default)
			)
			(layer "B.Fab")
		)
		(fp_line
			(start -0.67945 -0.3048)
			(end -0.67945 0.3048)
			(stroke
				(width 0.1)
				(type default)
			)
			(layer "B.Fab")
		)
		(fp_line
			(start 0.12065 -0.2794)
			(end -0.12065 -0.2794)
			(stroke
				(width 0.1)
				(type default)
			)
			(layer "B.Fab")
		)
		(fp_line
			(start -0.12065 -0.2794)
			(end -0.12065 -0.3048)
			(stroke
				(width 0.1)
				(type default)
			)
			(layer "B.Fab")
		)
		(fp_line
			(start 0.12065 0.2794)
			(end 0.12065 0.3048)
			(stroke
				(width 0.1)
				(type default)
			)
			(layer "B.Fab")
		)
		(fp_line
			(start -0.120396 0.2794)
			(end 0.12065 0.2794)
			(stroke
				(width 0.1)
				(type default)
			)
			(layer "B.Fab")
		)
		(fp_line
			(start 0.67945 0.3048)
			(end 0.67945 -0.305054)
			(stroke
				(width 0.1)
				(type default)
			)
			(layer "B.Fab")
		)
		(fp_line
			(start 0.12065 0.3048)
			(end 0.67945 0.3048)
			(stroke
				(width 0.1)
				(type default)
			)
			(layer "B.Fab")
		)
		(fp_line
			(start -0.120396 0.3048)
			(end -0.120396 0.2794)
			(stroke
				(width 0.1)
				(type default)
			)
			(layer "B.Fab")
		)
		(fp_line
			(start -0.67945 0.3048)
			(end -0.120396 0.3048)
			(stroke
				(width 0.1)
				(type default)
			)
			(layer "B.Fab")
		)
		(pad "1" smd circle
			(at 0.40005 0 270)
			(size 0 0)
			(layers "B.Cu" "B.Mask" "B.Paste")
			(net "FAN_7_TEMP")
		)
		(pad "2" smd circle
			(at -0.40005 0 270)
			(size 0 0)
			(layers "B.Cu" "B.Mask" "B.Paste")
			(net "GND")
		)
	)
	(footprint ""
		(layer "B.Cu")
		(at 3.81 -67.945 90)
		(property "Reference" "U392"
			(at -0.889 1.75133 270)
			(unlocked yes)
			(layer "B.SilkS")
			(effects
				(font
					(size 0.7874 0.5842)
					(thickness 0.1524)
				)
				(justify left mirror)
			)
		)
		(property "Value" ""
			(at 0 0 90)
			(layer "B.Fab")
			(effects
				(font
					(size 1.27 1.27)
				)
				(justify mirror)
			)
		)
		(duplicate_pad_numbers_are_jumpers no)
		(fp_line
			(start 1.3462 -1.1938)
			(end 1.3462 1.1684)
			(stroke
				(width 0.1524)
				(type default)
			)
			(layer "B.SilkS")
		)
		(fp_line
			(start -1.3462 -1.1938)
			(end 1.3462 -1.1938)
			(stroke
				(width 0.1524)
				(type default)
			)
			(layer "B.SilkS")
		)
		(fp_line
			(start 1.3462 1.1938)
			(end -1.3462 1.1938)
			(stroke
				(width 0.1524)
				(type default)
			)
			(layer "B.SilkS")
		)
		(fp_line
			(start -1.3462 1.1938)
			(end -1.3462 -1.1938)
			(stroke
				(width 0.1524)
				(type default)
			)
			(layer "B.SilkS")
		)
		(fp_poly
			(pts
				(xy 1.305306 -1.378712) (xy 1.947164 -1.59258) (xy 1.519174 -2.020316)
			)
			(stroke
				(width 0)
				(type default)
			)
			(fill yes)
			(layer "B.SilkS")
		)
		(fp_line
			(start 0.674878 -1.124966)
			(end 0.674878 1.124966)
			(stroke
				(width 0.1)
				(type default)
			)
			(layer "B.Fab")
		)
		(fp_line
			(start -0.674878 -1.124966)
			(end 0.674878 -1.124966)
			(stroke
				(width 0.1)
				(type default)
			)
			(layer "B.Fab")
		)
		(fp_line
			(start 0.674878 1.124966)
			(end -0.674878 1.124966)
			(stroke
				(width 0.1)
				(type default)
			)
			(layer "B.Fab")
		)
		(fp_line
			(start -0.674878 1.124966)
			(end -0.674878 -1.124966)
			(stroke
				(width 0.1)
				(type default)
			)
			(layer "B.Fab")
		)
		(fp_poly
			(pts
				(xy 1.447038 -0.760476) (xy 2.052066 -0.457962) (xy 2.052066 -1.06299)
			)
			(stroke
				(width 0)
				(type default)
			)
			(fill yes)
			(layer "B.Fab")
		)
		(pad "1" smd rect
			(at 0.899922 -0.750062 270)
			(size 0.6096 0.6096)
			(layers "B.Cu" "B.Mask" "B.Paste")
			(net "NC_U392_P1")
		)
		(pad "2" smd rect
			(at 0.899922 0 180)
			(size 0.4064 0.6096)
			(layers "B.Cu" "B.Mask" "B.Paste")
			(net "FAN_4_PRSNT_BUF_N")
		)
		(pad "3" smd rect
			(at 0.899922 0.750062 270)
			(size 0.6096 0.6096)
			(layers "B.Cu" "B.Mask" "B.Paste")
			(net "GND")
		)
		(pad "4" smd rect
			(at -0.899922 0.750062 270)
			(size 0.6096 0.6096)
			(layers "B.Cu" "B.Mask" "B.Paste")
			(net "FAN_4_PRESENT")
		)
		(pad "5" smd rect
			(at -0.899922 -0.750062 270)
			(size 0.6096 0.6096)
			(layers "B.Cu" "B.Mask" "B.Paste")
			(net "P3V3_AUX")
		)
	)
	(footprint ""
		(layer "B.Cu")
		(at 4.699 -249.428 -90)
		(property "Reference" "PC53"
			(at 0 0 90)
			(layer "B.SilkS")
			(hide yes)
			(effects
				(font
					(size 1.27 1.27)
				)
				(justify mirror)
			)
		)
		(property "Value" ""
			(at 0 0 90)
			(layer "B.Fab")
			(effects
				(font
					(size 1.27 1.27)
				)
				(justify mirror)
			)
		)
		(duplicate_pad_numbers_are_jumpers no)
		(fp_line
			(start -0.7874 0.4064)
			(end 0.7874 0.4064)
			(stroke
				(width 0.1524)
				(type default)
			)
			(layer "B.SilkS")
		)
		(fp_line
			(start 0.7874 0.4064)
			(end 0.7874 -0.4064)
			(stroke
				(width 0.1524)
				(type default)
			)
			(layer "B.SilkS")
		)
		(fp_line
			(start -0.7874 -0.4064)
			(end -0.7874 0.4064)
			(stroke
				(width 0.1524)
				(type default)
			)
			(layer "B.SilkS")
		)
		(fp_line
			(start 0.7874 -0.4064)
			(end -0.7874 -0.4064)
			(stroke
				(width 0.1524)
				(type default)
			)
			(layer "B.SilkS")
		)
		(fp_line
			(start -0.67945 0.3048)
			(end -0.120396 0.3048)
			(stroke
				(width 0.1)
				(type default)
			)
			(layer "B.Fab")
		)
		(fp_line
			(start -0.120396 0.3048)
			(end -0.120396 0.2794)
			(stroke
				(width 0.1)
				(type default)
			)
			(layer "B.Fab")
		)
		(fp_line
			(start 0.12065 0.3048)
			(end 0.67945 0.3048)
			(stroke
				(width 0.1)
				(type default)
			)
			(layer "B.Fab")
		)
		(fp_line
			(start 0.67945 0.3048)
			(end 0.67945 -0.305054)
			(stroke
				(width 0.1)
				(type default)
			)
			(layer "B.Fab")
		)
		(fp_line
			(start -0.120396 0.2794)
			(end 0.12065 0.2794)
			(stroke
				(width 0.1)
				(type default)
			)
			(layer "B.Fab")
		)
		(fp_line
			(start 0.12065 0.2794)
			(end 0.12065 0.3048)
			(stroke
				(width 0.1)
				(type default)
			)
			(layer "B.Fab")
		)
		(fp_line
			(start -0.12065 -0.2794)
			(end -0.12065 -0.3048)
			(stroke
				(width 0.1)
				(type default)
			)
			(layer "B.Fab")
		)
		(fp_line
			(start 0.12065 -0.2794)
			(end -0.12065 -0.2794)
			(stroke
				(width 0.1)
				(type default)
			)
			(layer "B.Fab")
		)
		(fp_line
			(start -0.67945 -0.3048)
			(end -0.67945 0.3048)
			(stroke
				(width 0.1)
				(type default)
			)
			(layer "B.Fab")
		)
		(fp_line
			(start -0.12065 -0.3048)
			(end -0.67945 -0.3048)
			(stroke
				(width 0.1)
				(type default)
			)
			(layer "B.Fab")
		)
		(fp_line
			(start 0.12065 -0.305054)
			(end 0.12065 -0.2794)
			(stroke
				(width 0.1)
				(type default)
			)
			(layer "B.Fab")
		)
		(fp_line
			(start 0.67945 -0.305054)
			(end 0.12065 -0.305054)
			(stroke
				(width 0.1)
				(type default)
			)
			(layer "B.Fab")
		)
		(pad "1" smd circle
			(at 0.40005 0 90)
			(size 0 0)
			(layers "B.Cu" "B.Mask" "B.Paste")
			(net "FAN_6_TIMER")
		)
		(pad "2" smd circle
			(at -0.40005 0 90)
			(size 0 0)
			(layers "B.Cu" "B.Mask" "B.Paste")
			(net "GND")
		)
	)
)
